# S9S_MB_2U (Grand Teton) — schematic netlist excerpt (pin names and nets, part order shuffled) for the footprints in the layout excerpt that follows; sources: Cadence DE-HDL packaged netlist, KiCad conversion of 03242023_DA0F0TMBIJ0_F0T_Motherboard_J_brd_V01_OCP.brd

C2339  Q_CAP  0.1UF 25V 10% X7R  pkg 0402  page 211 : A = P3V3_9ZXL045_VDD ; B = GND
PC2191  Q_CAP  0.068UF 16V 10% X7R  pkg 0402  page 301 : A = HSC_SS ; B = AGND_HSC

(kicad_pcb
	(version 20260206)
	(generator "pcbnew")
	(generator_version "10.0")
	(general
		(thickness 1.6)
		(legacy_teardrops no)
	)
	(paper "A4")
	(title_block
		(title "03242023_DA0F0TMBIJ0_F0T_Motherboard_J_brd_V01_OCP.brd")
		(comment 1 "Grand Teton / footprints 4607-4608 of 6105")
	)
	(layers
		(0 "F.Cu" signal "TOP")
		(4 "In1.Cu" signal "GND")
		(6 "In2.Cu" signal "IN1")
		(8 "In3.Cu" signal "GND1")
		(10 "In4.Cu" signal "IN2")
		(12 "In5.Cu" signal "GND2")
		(14 "In6.Cu" signal "IN3")
		(16 "In7.Cu" signal "GND3")
		(18 "In8.Cu" signal "VCC")
		(20 "In9.Cu" signal "VCC1")
		(22 "In10.Cu" signal "GND4")
		(24 "In11.Cu" signal "IN4")
		(26 "In12.Cu" signal "GND5")
		(28 "In13.Cu" signal "IN5")
		(30 "In14.Cu" signal "GND6")
		(32 "In15.Cu" signal "IN6")
		(34 "In16.Cu" signal "GND7")
		(2 "B.Cu" signal "BOTTOM")
		(9 "F.Adhes" user "F.Adhesive")
		(11 "B.Adhes" user "B.Adhesive")
		(13 "F.Paste" user "Package Geometry/Pastemask Top")
		(15 "B.Paste" user "Package Geometry/Pastemask Bottom")
		(5 "F.SilkS" user "Ref Des/Silkscreen Top")
		(7 "B.SilkS" user "Ref Des/Silkscreen Bottom")
		(1 "F.Mask" user "Board Geometry/Soldermask Top")
		(3 "B.Mask" user "Board Geometry/Soldermask Bottom")
		(17 "Dwgs.User" user "User.Drawings")
		(19 "Cmts.User" user "User.Comments")
		(21 "Eco1.User" user "User.Eco1")
		(23 "Eco2.User" user "User.Eco2")
		(25 "Edge.Cuts" user "Board Geometry/Outline")
		(27 "Margin" user)
		(31 "F.CrtYd" user "Package Geometry/Place Bound Top")
		(29 "B.CrtYd" user "Package Geometry/Place Bound Bottom")
		(35 "F.Fab" user "Ref Des/Assembly Top")
		(33 "B.Fab" user "Ref Des/Assembly Bottom")
	)
	(footprint ""
		(layer "B.Cu")
		(at 111.82858 -411.676088 -90)
		(property "Reference" "C2339"
			(at 0 0 90)
			(layer "B.SilkS")
			(hide yes)
			(effects
				(font
					(size 1.27 1.27)
				)
				(justify mirror)
			)
		)
		(property "Value" ""
			(at 0 0 90)
			(layer "B.Fab")
			(effects
				(font
					(size 1.27 1.27)
				)
				(justify mirror)
			)
		)
		(duplicate_pad_numbers_are_jumpers no)
		(fp_line
			(start -0.7874 0.4064)
			(end 0.7874 0.4064)
			(stroke
				(width 0.1524)
				(type default)
			)
			(layer "B.SilkS")
		)
		(fp_line
			(start 0.7874 0.4064)
			(end 0.7874 -0.4064)
			(stroke
				(width 0.1524)
				(type default)
			)
			(layer "B.SilkS")
		)
		(fp_line
			(start -0.7874 -0.4064)
			(end -0.7874 0.4064)
			(stroke
				(width 0.1524)
				(type default)
			)
			(layer "B.SilkS")
		)
		(fp_line
			(start 0.7874 -0.4064)
			(end -0.7874 -0.4064)
			(stroke
				(width 0.1524)
				(type default)
			)
			(layer "B.SilkS")
		)
		(fp_line
			(start -0.67945 0.3048)
			(end -0.120396 0.3048)
			(stroke
				(width 0.1)
				(type default)
			)
			(layer "B.Fab")
		)
		(fp_line
			(start -0.120396 0.3048)
			(end -0.120396 0.2794)
			(stroke
				(width 0.1)
				(type default)
			)
			(layer "B.Fab")
		)
		(fp_line
			(start 0.12065 0.3048)
			(end 0.67945 0.3048)
			(stroke
				(width 0.1)
				(type default)
			)
			(layer "B.Fab")
		)
		(fp_line
			(start 0.67945 0.3048)
			(end 0.67945 -0.305054)
			(stroke
				(width 0.1)
				(type default)
			)
			(layer "B.Fab")
		)
		(fp_line
			(start -0.120396 0.2794)
			(end 0.12065 0.2794)
			(stroke
				(width 0.1)
				(type default)
			)
			(layer "B.Fab")
		)
		(fp_line
			(start 0.12065 0.2794)
			(end 0.12065 0.3048)
			(stroke
				(width 0.1)
				(type default)
			)
			(layer "B.Fab")
		)
		(fp_line
			(start -0.12065 -0.2794)
			(end -0.12065 -0.3048)
			(stroke
				(width 0.1)
				(type default)
			)
			(layer "B.Fab")
		)
		(fp_line
			(start 0.12065 -0.2794)
			(end -0.12065 -0.2794)
			(stroke
				(width 0.1)
				(type default)
			)
			(layer "B.Fab")
		)
		(fp_line
			(start -0.67945 -0.3048)
			(end -0.67945 0.3048)
			(stroke
				(width 0.1)
				(type default)
			)
			(layer "B.Fab")
		)
		(fp_line
			(start -0.12065 -0.3048)
			(end -0.67945 -0.3048)
			(stroke
				(width 0.1)
				(type default)
			)
			(layer "B.Fab")
		)
		(fp_line
			(start 0.12065 -0.305054)
			(end 0.12065 -0.2794)
			(stroke
				(width 0.1)
				(type default)
			)
			(layer "B.Fab")
		)
		(fp_line
			(start 0.67945 -0.305054)
			(end 0.12065 -0.305054)
			(stroke
				(width 0.1)
				(type default)
			)
			(layer "B.Fab")
		)
		(pad "1" smd circle
			(at 0.40005 0 90)
			(size 0 0)
			(layers "B.Cu" "B.Mask" "B.Paste")
			(net "P3V3_9ZXL045_VDD")
		)
		(pad "2" smd circle
			(at -0.40005 0 90)
			(size 0 0)
			(layers "B.Cu" "B.Mask" "B.Paste")
			(net "GND")
		)
	)
	(footprint ""
		(layer "B.Cu")
		(at 179.352448 -403.271482)
		(property "Reference" "PC2191"
			(at 0 0 0)
			(layer "B.SilkS")
			(hide yes)
			(effects
				(font
					(size 1.27 1.27)
				)
				(justify mirror)
			)
		)
		(property "Value" ""
			(at 0 0 0)
			(layer "B.Fab")
			(effects
				(font
					(size 1.27 1.27)
				)
				(justify mirror)
			)
		)
		(duplicate_pad_numbers_are_jumpers no)
		(fp_line
			(start -0.7874 -0.4064)
			(end -0.7874 0.4064)
			(stroke
				(width 0.1524)
				(type default)
			)
			(layer "B.SilkS")
		)
		(fp_line
			(start -0.7874 0.4064)
			(end 0.7874 0.4064)
			(stroke
				(width 0.1524)
				(type default)
			)
			(layer "B.SilkS")
		)
		(fp_line
			(start 0.7874 -0.4064)
			(end -0.7874 -0.4064)
			(stroke
				(width 0.1524)
				(type default)
			)
			(layer "B.SilkS")
		)
		(fp_line
			(start 0.7874 0.4064)
			(end 0.7874 -0.4064)
			(stroke
				(width 0.1524)
				(type default)
			)
			(layer "B.SilkS")
		)
		(fp_line
			(start -0.67945 -0.3048)
			(end -0.67945 0.3048)
			(stroke
				(width 0.1)
				(type default)
			)
			(layer "B.Fab")
		)
		(fp_line
			(start -0.67945 0.3048)
			(end -0.120396 0.3048)
			(stroke
				(width 0.1)
				(type default)
			)
			(layer "B.Fab")
		)
		(fp_line
			(start -0.12065 -0.3048)
			(end -0.67945 -0.3048)
			(stroke
				(width 0.1)
				(type default)
			)
			(layer "B.Fab")
		)
		(fp_line
			(start -0.12065 -0.2794)
			(end -0.12065 -0.3048)
			(stroke
				(width 0.1)
				(type default)
			)
			(layer "B.Fab")
		)
		(fp_line
			(start -0.120396 0.2794)
			(end 0.12065 0.2794)
			(stroke
				(width 0.1)
				(type default)
			)
			(layer "B.Fab")
		)
		(fp_line
			(start -0.120396 0.3048)
			(end -0.120396 0.2794)
			(stroke
				(width 0.1)
				(type default)
			)
			(layer "B.Fab")
		)
		(fp_line
			(start 0.12065 -0.305054)
			(end 0.12065 -0.2794)
			(stroke
				(width 0.1)
				(type default)
			)
			(layer "B.Fab")
		)
		(fp_line
			(start 0.12065 -0.2794)
			(end -0.12065 -0.2794)
			(stroke
				(width 0.1)
				(type default)
			)
			(layer "B.Fab")
		)
		(fp_line
			(start 0.12065 0.2794)
			(end 0.12065 0.3048)
			(stroke
				(width 0.1)
				(type default)
			)
			(layer "B.Fab")
		)
		(fp_line
			(start 0.12065 0.3048)
			(end 0.67945 0.3048)
			(stroke
				(width 0.1)
				(type default)
			)
			(layer "B.Fab")
		)
		(fp_line
			(start 0.67945 -0.305054)
			(end 0.12065 -0.305054)
			(stroke
				(width 0.1)
				(type default)
			)
			(layer "B.Fab")
		)
		(fp_line
			(start 0.67945 0.3048)
			(end 0.67945 -0.305054)
			(stroke
				(width 0.1)
				(type default)
			)
			(layer "B.Fab")
		)
		(pad "1" smd circle
			(at 0.40005 0 180)
			(size 0 0)
			(layers "B.Cu" "B.Mask" "B.Paste")
			(net "HSC_SS")
		)
		(pad "2" smd circle
			(at -0.40005 0 180)
			(size 0 0)
			(layers "B.Cu" "B.Mask" "B.Paste")
			(net "AGND_HSC")
		)
	)
)
